(kicad_pcb
	(version 20260206)
	(generator "pcbnew")
	(generator_version "10.0")
	(general
		(thickness 1.6)
		(legacy_teardrops no)
	)
	(paper "A4")
	(title_block
		(title "01162023_DA0F0TEBIF0_F0T_Expander_BD_F_brd_V02_OCP.brd")
		(comment 1 "Grand Teton / footprints 9562-9568 of 9728")
	)
	(layers
		(0 "F.Cu" signal "TOP")
		(4 "In1.Cu" signal "GND")
		(6 "In2.Cu" signal "VCC")
		(8 "In3.Cu" signal "VCC1")
		(10 "In4.Cu" signal "GND1")
		(12 "In5.Cu" signal "IN1")
		(14 "In6.Cu" signal "GND2")
		(16 "In7.Cu" signal "IN2")
		(18 "In8.Cu" signal "GND3")
		(20 "In9.Cu" signal "IN3")
		(22 "In10.Cu" signal "GND4")
		(24 "In11.Cu" signal "IN4")
		(26 "In12.Cu" signal "GND5")
		(28 "In13.Cu" signal "IN5")
		(30 "In14.Cu" signal "GND6")
		(32 "In15.Cu" signal "IN6")
		(34 "In16.Cu" signal "GND7")
		(2 "B.Cu" signal "BOTTOM")
		(9 "F.Adhes" user "F.Adhesive")
		(11 "B.Adhes" user "B.Adhesive")
		(13 "F.Paste" user "Package Geometry/Pastemask Top")
		(15 "B.Paste" user "Package Geometry/Pastemask Bottom")
		(5 "F.SilkS" user "Ref Des/Silkscreen Top")
		(7 "B.SilkS" user "Ref Des/Silkscreen Bottom")
		(1 "F.Mask" user "Board Geometry/Soldermask Top")
		(3 "B.Mask" user "Board Geometry/Soldermask Bottom")
		(17 "Dwgs.User" user "User.Drawings")
		(19 "Cmts.User" user "User.Comments")
		(21 "Eco1.User" user "User.Eco1")
		(23 "Eco2.User" user "User.Eco2")
		(25 "Edge.Cuts" user "Board Geometry/Outline")
		(27 "Margin" user)
		(31 "F.CrtYd" user "Package Geometry/Place Bound Top")
		(29 "B.CrtYd" user "Package Geometry/Place Bound Bottom")
		(35 "F.Fab" user "Ref Des/Assembly Top")
		(33 "B.Fab" user "Ref Des/Assembly Bottom")
	)
	(footprint ""
		(layer "B.Cu")
		(at 130.15722 -319.420494 -90)
		(property "Reference" "R5787"
			(at 0 0 90)
			(layer "B.SilkS")
			(hide yes)
			(effects
				(font
					(size 1.27 1.27)
				)
				(justify mirror)
			)
		)
		(property "Value" ""
			(at 0 0 90)
			(layer "B.Fab")
			(effects
				(font
					(size 1.27 1.27)
				)
				(justify mirror)
			)
		)
		(duplicate_pad_numbers_are_jumpers no)
		(fp_line
			(start -2.576322 1.1303)
			(end 2.576322 1.1303)
			(stroke
				(width 0.1524)
				(type default)
			)
			(layer "B.SilkS")
		)
		(fp_line
			(start 2.576322 1.1303)
			(end 2.576322 -1.1303)
			(stroke
				(width 0.1524)
				(type default)
			)
			(layer "B.SilkS")
		)
		(fp_line
			(start -2.576322 -1.1303)
			(end -2.576322 1.1303)
			(stroke
				(width 0.1524)
				(type default)
			)
			(layer "B.SilkS")
		)
		(fp_line
			(start 2.576322 -1.1303)
			(end -2.576322 -1.1303)
			(stroke
				(width 0.1524)
				(type default)
			)
			(layer "B.SilkS")
		)
		(fp_line
			(start -1.649984 0.899922)
			(end -1.649984 -0.899922)
			(stroke
				(width 0.1)
				(type default)
			)
			(layer "B.Fab")
		)
		(fp_line
			(start 1.649984 0.899922)
			(end -1.649984 0.899922)
			(stroke
				(width 0.1)
				(type default)
			)
			(layer "B.Fab")
		)
		(fp_line
			(start -1.649984 -0.899922)
			(end 1.649984 -0.899922)
			(stroke
				(width 0.1)
				(type default)
			)
			(layer "B.Fab")
		)
		(fp_line
			(start 1.649984 -0.899922)
			(end 1.649984 0.899922)
			(stroke
				(width 0.1)
				(type default)
			)
			(layer "B.Fab")
		)
		(pad "1A" smd rect
			(at 1.700022 0 90)
			(size 1.4986 2.0066)
			(layers "B.Cu" "B.Mask" "B.Paste")
			(net "P0V8_PEX1")
		)
		(pad "1B" smd rect
			(at 1.077722 0 90)
			(size 0.254 0.508)
			(layers "B.Cu" "B.Mask" "B.Paste")
			(net "P0V8_PEX1")
		)
		(pad "2A" smd rect
			(at -1.700022 0 90)
			(size 1.4986 2.0066)
			(layers "B.Cu" "B.Mask" "B.Paste")
			(net "P0V8_SERDES_VDDA_PEX1")
		)
		(pad "2B" smd rect
			(at -1.077722 0 90)
			(size 0.254 0.508)
			(layers "B.Cu" "B.Mask" "B.Paste")
			(net "P0V8_SERDES_VDDA_PEX1")
		)
	)
	(footprint ""
		(layer "B.Cu")
		(at 397.85544 -151.9936)
		(property "Reference" "R324"
			(at 0 0 0)
			(layer "B.SilkS")
			(hide yes)
			(effects
				(font
					(size 1.27 1.27)
				)
				(justify mirror)
			)
		)
		(property "Value" ""
			(at 0 0 0)
			(layer "B.Fab")
			(effects
				(font
					(size 1.27 1.27)
				)
				(justify mirror)
			)
		)
		(duplicate_pad_numbers_are_jumpers no)
		(fp_line
			(start -0.7874 -0.4064)
			(end -0.7874 0.4064)
			(stroke
				(width 0.1524)
				(type default)
			)
			(layer "B.SilkS")
		)
		(fp_line
			(start -0.7874 0.4064)
			(end 0.7874 0.4064)
			(stroke
				(width 0.1524)
				(type default)
			)
			(layer "B.SilkS")
		)
		(fp_line
			(start 0.7874 -0.4064)
			(end -0.7874 -0.4064)
			(stroke
				(width 0.1524)
				(type default)
			)
			(layer "B.SilkS")
		)
		(fp_line
			(start 0.7874 0.4064)
			(end 0.7874 -0.4064)
			(stroke
				(width 0.1524)
				(type default)
			)
			(layer "B.SilkS")
		)
		(fp_line
			(start -0.67945 -0.3048)
			(end -0.67945 0.3048)
			(stroke
				(width 0.1)
				(type default)
			)
			(layer "B.Fab")
		)
		(fp_line
			(start -0.67945 0.3048)
			(end -0.120396 0.3048)
			(stroke
				(width 0.1)
				(type default)
			)
			(layer "B.Fab")
		)
		(fp_line
			(start -0.12065 -0.3048)
			(end -0.67945 -0.3048)
			(stroke
				(width 0.1)
				(type default)
			)
			(layer "B.Fab")
		)
		(fp_line
			(start -0.12065 -0.2794)
			(end -0.12065 -0.3048)
			(stroke
				(width 0.1)
				(type default)
			)
			(layer "B.Fab")
		)
		(fp_line
			(start -0.120396 0.2794)
			(end 0.12065 0.2794)
			(stroke
				(width 0.1)
				(type default)
			)
			(layer "B.Fab")
		)
		(fp_line
			(start -0.120396 0.3048)
			(end -0.120396 0.2794)
			(stroke
				(width 0.1)
				(type default)
			)
			(layer "B.Fab")
		)
		(fp_line
			(start 0.12065 -0.305054)
			(end 0.12065 -0.2794)
			(stroke
				(width 0.1)
				(type default)
			)
			(layer "B.Fab")
		)
		(fp_line
			(start 0.12065 -0.2794)
			(end -0.12065 -0.2794)
			(stroke
				(width 0.1)
				(type default)
			)
			(layer "B.Fab")
		)
		(fp_line
			(start 0.12065 0.2794)
			(end 0.12065 0.3048)
			(stroke
				(width 0.1)
				(type default)
			)
			(layer "B.Fab")
		)
		(fp_line
			(start 0.12065 0.3048)
			(end 0.67945 0.3048)
			(stroke
				(width 0.1)
				(type default)
			)
			(layer "B.Fab")
		)
		(fp_line
			(start 0.67945 -0.305054)
			(end 0.12065 -0.305054)
			(stroke
				(width 0.1)
				(type default)
			)
			(layer "B.Fab")
		)
		(fp_line
			(start 0.67945 0.3048)
			(end 0.67945 -0.305054)
			(stroke
				(width 0.1)
				(type default)
			)
			(layer "B.Fab")
		)
		(pad "1" smd circle
			(at 0.40005 0 180)
			(size 0 0)
			(layers "B.Cu" "B.Mask" "B.Paste")
			(net "NCSI_NIC6_TXD0")
		)
		(pad "2" smd circle
			(at -0.40005 0 180)
			(size 0 0)
			(layers "B.Cu" "B.Mask" "B.Paste")
			(net "GND")
		)
	)
	(footprint ""
		(layer "B.Cu")
		(at 338.893912 -226.787202 -90)
		(property "Reference" "C2029"
			(at 0 0 90)
			(layer "B.SilkS")
			(hide yes)
			(effects
				(font
					(size 1.27 1.27)
				)
				(justify mirror)
			)
		)
		(property "Value" ""
			(at 0 0 90)
			(layer "B.Fab")
			(effects
				(font
					(size 1.27 1.27)
				)
				(justify mirror)
			)
		)
		(duplicate_pad_numbers_are_jumpers no)
		(fp_line
			(start -0.69215 0.2921)
			(end 0.69215 0.2921)
			(stroke
				(width 0.1524)
				(type default)
			)
			(layer "B.SilkS")
		)
		(fp_line
			(start 0.69215 0.2921)
			(end 0.69215 -0.2921)
			(stroke
				(width 0.1524)
				(type default)
			)
			(layer "B.SilkS")
		)
		(fp_line
			(start -0.69215 -0.2921)
			(end -0.69215 0.2921)
			(stroke
				(width 0.1524)
				(type default)
			)
			(layer "B.SilkS")
		)
		(fp_line
			(start 0.69215 -0.2921)
			(end -0.69215 -0.2921)
			(stroke
				(width 0.1524)
				(type default)
			)
			(layer "B.SilkS")
		)
		(fp_line
			(start -0.51435 0.2794)
			(end 0.51435 0.2794)
			(stroke
				(width 0.1)
				(type default)
			)
			(layer "B.Fab")
		)
		(fp_line
			(start 0.51435 0.2794)
			(end 0.51435 -0.2794)
			(stroke
				(width 0.1)
				(type default)
			)
			(layer "B.Fab")
		)
		(fp_line
			(start -0.51435 -0.2794)
			(end -0.51435 0.2794)
			(stroke
				(width 0.1)
				(type default)
			)
			(layer "B.Fab")
		)
		(fp_line
			(start 0.51435 -0.2794)
			(end -0.51435 -0.2794)
			(stroke
				(width 0.1)
				(type default)
			)
			(layer "B.Fab")
		)
		(pad "1" smd circle
			(at 0.40005 0 90)
			(size 0 0)
			(layers "B.Cu" "B.Mask" "B.Paste")
			(net "P3V3_FPGA_VCCIO0")
		)
		(pad "2" smd circle
			(at -0.40005 0 90)
			(size 0 0)
			(layers "B.Cu" "B.Mask" "B.Paste")
			(net "GND")
		)
		(zone
			(layer "B.Cu")
			(hatch none 0.5)
			(connect_pads
				(clearance 0)
			)
			(min_thickness 0.25)
			(keepout
				(tracks not_allowed)
				(vias allowed)
				(pads allowed)
				(copperpour not_allowed)
				(footprints allowed)
			)
			(placement
				(enabled no)
				(sheetname "")
			)
			(fill
				(thermal_gap 0.5)
				(thermal_bridge_width 0.5)
				(island_removal_mode 0)
			)
			(polygon
				(pts
					(xy 338.806282 -226.596702) (xy 338.748116 -226.688142) (xy 338.748116 -226.887532) (xy 338.806282 -226.977702)
					(xy 338.981542 -226.977702) (xy 339.039962 -226.887532) (xy 339.039962 -226.688142) (xy 338.981796 -226.596702)
				)
			)
		)
	)
	(footprint ""
		(layer "B.Cu")
		(at 373.035322 -247.441974 180)
		(property "Reference" "U103"
			(at 0.169926 2.10058 0)
			(unlocked yes)
			(layer "B.SilkS")
			(effects
				(font
					(size 0.7874 0.5842)
					(thickness 0.1524)
				)
				(justify mirror)
			)
		)
		(property "Value" ""
			(at 0 0 0)
			(layer "B.Fab")
			(effects
				(font
					(size 1.27 1.27)
				)
				(justify mirror)
			)
		)
		(duplicate_pad_numbers_are_jumpers no)
		(fp_line
			(start 1.7272 1.1176)
			(end 1.7272 -1.1176)
			(stroke
				(width 0.1524)
				(type default)
			)
			(layer "B.SilkS")
		)
		(fp_line
			(start 0.254 -1.1176)
			(end 1.7272 -1.1176)
			(stroke
				(width 0.1524)
				(type default)
			)
			(layer "B.SilkS")
		)
		(fp_line
			(start 0 -0.7366)
			(end 0.254 -1.1176)
			(stroke
				(width 0.1524)
				(type default)
			)
			(layer "B.SilkS")
		)
		(fp_line
			(start -0.254 -1.1176)
			(end 0 -0.7366)
			(stroke
				(width 0.1524)
				(type default)
			)
			(layer "B.SilkS")
		)
		(fp_line
			(start -1.7272 1.1176)
			(end 1.7272 1.1176)
			(stroke
				(width 0.1524)
				(type default)
			)
			(layer "B.SilkS")
		)
		(fp_line
			(start -1.7272 -1.1176)
			(end -0.254 -1.1176)
			(stroke
				(width 0.1524)
				(type default)
			)
			(layer "B.SilkS")
		)
		(fp_line
			(start -1.7272 -1.1176)
			(end -1.7272 1.1176)
			(stroke
				(width 0.1524)
				(type default)
			)
			(layer "B.SilkS")
		)
		(fp_poly
			(pts
				(xy 1.9558 -0.649986) (xy 2.7178 -0.268986) (xy 2.7178 -1.030986)
			)
			(stroke
				(width 0)
				(type default)
			)
			(fill yes)
			(layer "B.SilkS")
		)
		(fp_line
			(start 1.5748 1.1176)
			(end -1.5748 1.1176)
			(stroke
				(width 0.1)
				(type default)
			)
			(layer "B.Fab")
		)
		(fp_line
			(start 1.5748 -1.1176)
			(end 1.5748 1.1176)
			(stroke
				(width 0.1)
				(type default)
			)
			(layer "B.Fab")
		)
		(fp_line
			(start -1.5748 1.1176)
			(end -1.5748 -1.1176)
			(stroke
				(width 0.1)
				(type default)
			)
			(layer "B.Fab")
		)
		(fp_line
			(start -1.5748 -1.1176)
			(end 1.5748 -1.1176)
			(stroke
				(width 0.1)
				(type default)
			)
			(layer "B.Fab")
		)
		(fp_poly
			(pts
				(xy 1.9558 -0.649986) (xy 2.7178 -0.268986) (xy 2.7178 -1.030986)
			)
			(stroke
				(width 0)
				(type default)
			)
			(fill yes)
			(layer "B.Fab")
		)
		(pad "1" smd rect
			(at 0.999998 -0.649986 90)
			(size 0.3556 1.1176)
			(layers "B.Cu" "B.Mask" "B.Paste")
			(net "UART_PEX2_SDB_R_TX")
		)
		(pad "2" smd rect
			(at 0.999998 0 90)
			(size 0.3556 1.1176)
			(layers "B.Cu" "B.Mask" "B.Paste")
			(net "GND")
		)
		(pad "3" smd rect
			(at 0.999998 0.649986 90)
			(size 0.3556 1.1176)
			(layers "B.Cu" "B.Mask" "B.Paste")
			(net "UART_PEX3_SDB_R_TX")
		)
		(pad "4" smd rect
			(at -0.999998 0.649986 90)
			(size 0.3556 1.1176)
			(layers "B.Cu" "B.Mask" "B.Paste")
			(net "UART_PEX3_SDB_BUF_R_TX")
		)
		(pad "5" smd rect
			(at -0.999998 0 90)
			(size 0.3556 1.1176)
			(layers "B.Cu" "B.Mask" "B.Paste")
			(net "P1V8_PEX")
		)
		(pad "6" smd rect
			(at -0.999998 -0.649986 90)
			(size 0.3556 1.1176)
			(layers "B.Cu" "B.Mask" "B.Paste")
			(net "UART_PEX2_SDB_BUF_R_TX")
		)
	)
	(footprint ""
		(layer "B.Cu")
		(at 232.959402 -447.691764)
		(property "Reference" "X80"
			(at 0.1778 -1.92913 0)
			(unlocked yes)
			(layer "B.SilkS")
			(effects
				(font
					(size 0.7874 0.5842)
					(thickness 0.1524)
				)
				(justify left mirror)
			)
		)
		(property "Value" ""
			(at 0 0 0)
			(layer "B.Fab")
			(effects
				(font
					(size 1.27 1.27)
				)
				(justify mirror)
			)
		)
		(property "Device Type" "TP_TDR_4P_FTS_MPKT4_H025P0200_IO_TP15_TP_TDR_4P_DIP"
			(at -1.30175 1.27 270)
			(unlocked yes)
			(layer "B.Fab")
			(hide yes)
			(effects
				(font
					(size 0.635 0.4064)
					(thickness 0.1524)
				)
				(justify mirror)
			)
		)
		(property "User Part Number" "TP15"
			(at -1.30175 1.27 270)
			(unlocked yes)
			(layer "Cmts.User")
			(hide yes)
			(effects
				(font
					(size 0.635 0.4064)
					(thickness 0.1524)
				)
				(justify mirror)
			)
		)
		(duplicate_pad_numbers_are_jumpers no)
		(fp_line
			(start -2.54 -1.27)
			(end 0 -1.27)
			(stroke
				(width 0.1524)
				(type default)
			)
			(layer "B.SilkS")
		)
		(fp_line
			(start -2.54 -1.1303)
			(end -2.54 -1.27)
			(stroke
				(width 0.1524)
				(type default)
			)
			(layer "B.SilkS")
		)
		(fp_line
			(start -2.54 1.4097)
			(end -2.54 1.1303)
			(stroke
				(width 0.1524)
				(type default)
			)
			(layer "B.SilkS")
		)
		(fp_line
			(start -2.54 3.81)
			(end -2.54 3.6703)
			(stroke
				(width 0.1524)
				(type default)
			)
			(layer "B.SilkS")
		)
		(fp_line
			(start 0 -1.27)
			(end 0 -0.635)
			(stroke
				(width 0.1524)
				(type default)
			)
			(layer "B.SilkS")
		)
		(fp_line
			(start 0 0.635)
			(end 0 1.905)
			(stroke
				(width 0.1524)
				(type default)
			)
			(layer "B.SilkS")
		)
		(fp_line
			(start 0 3.175)
			(end 0 3.81)
			(stroke
				(width 0.1524)
				(type default)
			)
			(layer "B.SilkS")
		)
		(fp_line
			(start 0 3.81)
			(end -2.54 3.81)
			(stroke
				(width 0.1524)
				(type default)
			)
			(layer "B.SilkS")
		)
		(fp_poly
			(pts
				(xy 0.761746 0) (xy 2.285746 -0.762) (xy 2.285746 0.762)
			)
			(stroke
				(width 0)
				(type default)
			)
			(fill yes)
			(layer "B.SilkS")
		)
		(fp_line
			(start -2.54 -1.27)
			(end 0 -1.27)
			(stroke
				(width 0.1)
				(type default)
			)
			(layer "B.Fab")
		)
		(fp_line
			(start -2.54 3.81)
			(end -2.54 -1.27)
			(stroke
				(width 0.1)
				(type default)
			)
			(layer "B.Fab")
		)
		(fp_line
			(start 0 -1.27)
			(end 0 3.81)
			(stroke
				(width 0.1)
				(type default)
			)
			(layer "B.Fab")
		)
		(fp_line
			(start 0 3.81)
			(end -2.54 3.81)
			(stroke
				(width 0.1)
				(type default)
			)
			(layer "B.Fab")
		)
		(fp_poly
			(pts
				(xy 0.761746 0) (xy 2.285746 -0.762) (xy 2.285746 0.762)
			)
			(stroke
				(width 0)
				(type default)
			)
			(fill yes)
			(layer "B.Fab")
		)
		(pad "1" thru_hole circle
			(at 0 0 180)
			(size 1.0033 1.0033)
			(drill 0.249936)
			(layers "*.Cu" "*.Mask")
			(remove_unused_layers no)
			(net "TDR_DIFF_100_BOT_DIP")
			(clearance 0.10795)
			(padstack
				(mode front_inner_back)
				(layer "Inner"
					(shape circle)
					(size 0.8001 0.8001)
					(clearance 0.1524)
				)
				(layer "B.Cu"
					(shape circle)
					(size 1.0033 1.0033)
					(thermal_gap 0.10795)
					(clearance 0.10795)
				)
			)
		)
		(pad "2" thru_hole circle
			(at -2.54 0 180)
			(size 1.9939 1.9939)
			(drill 0.249936)
			(layers "*.Cu" "*.Mask")
			(remove_unused_layers no)
			(net "COUPON_GND1")
			(clearance 0.10795)
			(padstack
				(mode front_inner_back)
				(layer "Inner"
					(shape circle)
					(size 0.8001 0.8001)
					(clearance 0.1524)
				)
				(layer "B.Cu"
					(shape circle)
					(size 1.9939 1.9939)
					(thermal_gap 0.10795)
					(clearance 0.10795)
				)
			)
		)
		(pad "3" thru_hole circle
			(at -2.54 2.54 180)
			(size 1.9939 1.9939)
			(drill 0.249936)
			(layers "*.Cu" "*.Mask")
			(remove_unused_layers no)
			(net "COUPON_GND1")
			(clearance 0.10795)
			(padstack
				(mode front_inner_back)
				(layer "Inner"
					(shape circle)
					(size 0.8001 0.8001)
					(clearance 0.1524)
				)
				(layer "B.Cu"
					(shape circle)
					(size 1.9939 1.9939)
					(thermal_gap 0.10795)
					(clearance 0.10795)
				)
			)
		)
		(pad "4" thru_hole circle
			(at 0 2.54 180)
			(size 1.0033 1.0033)
			(drill 0.249936)
			(layers "*.Cu" "*.Mask")
			(remove_unused_layers no)
			(net "TDR_DIFF_100_BOT_DIN")
			(clearance 0.10795)
			(padstack
				(mode front_inner_back)
				(layer "Inner"
					(shape circle)
					(size 0.8001 0.8001)
					(clearance 0.1524)
				)
				(layer "B.Cu"
					(shape circle)
					(size 1.0033 1.0033)
					(thermal_gap 0.10795)
					(clearance 0.10795)
				)
			)
		)
	)
	(footprint ""
		(layer "B.Cu")
		(at 284.249876 -303.499774 -90)
		(property "Reference" "C3252"
			(at 0 0 90)
			(layer "B.SilkS")
			(hide yes)
			(effects
				(font
					(size 1.27 1.27)
				)
				(justify mirror)
			)
		)
		(property "Value" ""
			(at 0 0 90)
			(layer "B.Fab")
			(effects
				(font
					(size 1.27 1.27)
				)
				(justify mirror)
			)
		)
		(duplicate_pad_numbers_are_jumpers no)
		(fp_line
			(start -0.299974 0.150114)
			(end 0.299974 0.150114)
			(stroke
				(width 0.1)
				(type default)
			)
			(layer "B.Fab")
		)
		(fp_line
			(start 0.299974 0.150114)
			(end 0.299974 -0.150114)
			(stroke
				(width 0.1)
				(type default)
			)
			(layer "B.Fab")
		)
		(fp_line
			(start -0.299974 -0.150114)
			(end -0.299974 0.150114)
			(stroke
				(width 0.1)
				(type default)
			)
			(layer "B.Fab")
		)
		(fp_line
			(start 0.299974 -0.150114)
			(end -0.299974 -0.150114)
			(stroke
				(width 0.1)
				(type default)
			)
			(layer "B.Fab")
		)
		(pad "1" smd rect
			(at 0.2667 0 90)
			(size 0.3048 0.381)
			(layers "B.Cu" "B.Mask" "B.Paste")
			(net "P1V25_PEX2")
		)
		(pad "2" smd rect
			(at -0.2667 0 90)
			(size 0.3048 0.381)
			(layers "B.Cu" "B.Mask" "B.Paste")
			(net "GND")
		)
	)
	(footprint ""
		(layer "B.Cu")
		(at 400.349974 -303.499774 -90)
		(property "Reference" "C3433"
			(at 0 0 90)
			(layer "B.SilkS")
			(hide yes)
			(effects
				(font
					(size 1.27 1.27)
				)
				(justify mirror)
			)
		)
		(property "Value" ""
			(at 0 0 90)
			(layer "B.Fab")
			(effects
				(font
					(size 1.27 1.27)
				)
				(justify mirror)
			)
		)
		(duplicate_pad_numbers_are_jumpers no)
		(fp_line
			(start -0.299974 0.150114)
			(end 0.299974 0.150114)
			(stroke
				(width 0.1)
				(type default)
			)
			(layer "B.Fab")
		)
		(fp_line
			(start 0.299974 0.150114)
			(end 0.299974 -0.150114)
			(stroke
				(width 0.1)
				(type default)
			)
			(layer "B.Fab")
		)
		(fp_line
			(start -0.299974 -0.150114)
			(end -0.299974 0.150114)
			(stroke
				(width 0.1)
				(type default)
			)
			(layer "B.Fab")
		)
		(fp_line
			(start 0.299974 -0.150114)
			(end -0.299974 -0.150114)
			(stroke
				(width 0.1)
				(type default)
			)
			(layer "B.Fab")
		)
		(pad "1" smd rect
			(at 0.2667 0 90)
			(size 0.3048 0.381)
			(layers "B.Cu" "B.Mask" "B.Paste")
			(net "P1V25_PEX3")
		)
		(pad "2" smd rect
			(at -0.2667 0 90)
			(size 0.3048 0.381)
			(layers "B.Cu" "B.Mask" "B.Paste")
			(net "GND")
		)
	)
)
